# S9S_MB_2U (Grand Teton) — schematic netlist excerpt (pin names and nets, part order shuffled) for the footprints in the layout excerpt that follows; sources: Cadence DE-HDL packaged netlist, KiCad conversion of 03242023_DA0F0TMBIJ0_F0T_Motherboard_J_brd_V01_OCP.brd

PU13_P0_1  ISL99390FRZTR5935  ISL99390FRZ-TR5935 IC  pkg QFN21_6X5XB  page 267
  VOS  = PVCCIN_CPU0_VOS1
  AGND  = GND
  VCC  = PVCCIN_CPU0_VDD1
  PVCC  = PVCCIN_CPU0_PVCC
  PGND1  = GND
  GL1  = NC
  PGND2  = GND
  SW  = SW_PVCCIN_CPU0_SW1
  VIN1  = SW_P12V_PVCCIN_CPU0_FLT
  VIN2  = SW_P12V_PVCCIN_CPU0_FLT
  DNC  = NC
  PHASE  = SW_PVCCIN_CPU0_BOOTR1
  BOOT  = SW_PVCCIN_CPU0_BOOT1
  PWM  = PVCCIN_CPU0_PWM1
  EN  = PVCCIN_CPU0_VDD1
  TOUT_FLT  = PVCCIN_CPU0_ATSEN
  LSET  = PVCCIN_CPU0_LSET1
  IOUT  = PVCCIN_CPU0_IMON1
  REFIN  = PVCCIN_CPU0_VREF
  PGND3  = GND
  GL2  = NC

(kicad_pcb
	(version 20260206)
	(generator "pcbnew")
	(generator_version "10.0")
	(general
		(thickness 1.6)
		(legacy_teardrops no)
	)
	(paper "A4")
	(title_block
		(title "03242023_DA0F0TMBIJ0_F0T_Motherboard_J_brd_V01_OCP.brd")
		(comment 1 "Grand Teton / footprints 295-295 of 6105")
	)
	(layers
		(0 "F.Cu" signal "TOP")
		(4 "In1.Cu" signal "GND")
		(6 "In2.Cu" signal "IN1")
		(8 "In3.Cu" signal "GND1")
		(10 "In4.Cu" signal "IN2")
		(12 "In5.Cu" signal "GND2")
		(14 "In6.Cu" signal "IN3")
		(16 "In7.Cu" signal "GND3")
		(18 "In8.Cu" signal "VCC")
		(20 "In9.Cu" signal "VCC1")
		(22 "In10.Cu" signal "GND4")
		(24 "In11.Cu" signal "IN4")
		(26 "In12.Cu" signal "GND5")
		(28 "In13.Cu" signal "IN5")
		(30 "In14.Cu" signal "GND6")
		(32 "In15.Cu" signal "IN6")
		(34 "In16.Cu" signal "GND7")
		(2 "B.Cu" signal "BOTTOM")
		(9 "F.Adhes" user "F.Adhesive")
		(11 "B.Adhes" user "B.Adhesive")
		(13 "F.Paste" user "Package Geometry/Pastemask Top")
		(15 "B.Paste" user "Package Geometry/Pastemask Bottom")
		(5 "F.SilkS" user "Ref Des/Silkscreen Top")
		(7 "B.SilkS" user "Ref Des/Silkscreen Bottom")
		(1 "F.Mask" user "Board Geometry/Soldermask Top")
		(3 "B.Mask" user "Board Geometry/Soldermask Bottom")
		(17 "Dwgs.User" user "User.Drawings")
		(19 "Cmts.User" user "User.Comments")
		(21 "Eco1.User" user "User.Eco1")
		(23 "Eco2.User" user "User.Eco2")
		(25 "Edge.Cuts" user "Board Geometry/Outline")
		(27 "Margin" user)
		(31 "F.CrtYd" user "Package Geometry/Place Bound Top")
		(29 "B.CrtYd" user "Package Geometry/Place Bound Bottom")
		(35 "F.Fab" user "Ref Des/Assembly Top")
		(33 "B.Fab" user "Ref Des/Assembly Bottom")
	)
	(footprint ""
		(layer "F.Cu")
		(at 344.937588 -333.716122)
		(property "Reference" "PU13_P0_1"
			(at -2.66954 -6.20649 0)
			(unlocked yes)
			(layer "F.SilkS")
			(effects
				(font
					(size 0.7874 0.5842)
					(thickness 0.1524)
				)
				(justify left)
			)
		)
		(property "Value" ""
			(at 0 0 0)
			(layer "F.Fab")
			(effects
				(font
					(size 1.27 1.27)
				)
			)
		)
		(duplicate_pad_numbers_are_jumpers no)
		(fp_line
			(start -2.500122 -2.999994)
			(end -2.24409 -2.999994)
			(stroke
				(width 0.1524)
				(type default)
			)
			(layer "F.SilkS")
		)
		(fp_line
			(start -2.500122 -2.529078)
			(end -2.500122 -2.999994)
			(stroke
				(width 0.1524)
				(type default)
			)
			(layer "F.SilkS")
		)
		(fp_line
			(start -2.500122 0.6604)
			(end -2.500122 0.229108)
			(stroke
				(width 0.1524)
				(type default)
			)
			(layer "F.SilkS")
		)
		(fp_line
			(start -2.500122 2.999994)
			(end -2.500122 2.339594)
			(stroke
				(width 0.1524)
				(type default)
			)
			(layer "F.SilkS")
		)
		(fp_line
			(start -2.2987 2.999994)
			(end -2.500122 2.999994)
			(stroke
				(width 0.1524)
				(type default)
			)
			(layer "F.SilkS")
		)
		(fp_line
			(start 2.31394 -2.999994)
			(end 2.500122 -2.999994)
			(stroke
				(width 0.1524)
				(type default)
			)
			(layer "F.SilkS")
		)
		(fp_line
			(start 2.500122 -2.999994)
			(end 2.500122 -2.44348)
			(stroke
				(width 0.1524)
				(type default)
			)
			(layer "F.SilkS")
		)
		(fp_line
			(start 2.500122 2.339594)
			(end 2.500122 2.999994)
			(stroke
				(width 0.1524)
				(type default)
			)
			(layer "F.SilkS")
		)
		(fp_line
			(start 2.500122 2.999994)
			(end 2.2987 2.999994)
			(stroke
				(width 0.1524)
				(type default)
			)
			(layer "F.SilkS")
		)
		(fp_poly
			(pts
				(xy -2.218436 -3.60045) (xy -2.726436 -2.58445) (xy -3.234436 -3.60045)
			)
			(stroke
				(width 0)
				(type default)
			)
			(fill yes)
			(layer "F.SilkS")
		)
		(fp_line
			(start -2.500122 -2.999994)
			(end 2.500122 -2.999994)
			(stroke
				(width 0.1)
				(type default)
			)
			(layer "F.Fab")
		)
		(fp_line
			(start -2.500122 2.999994)
			(end -2.500122 -2.999994)
			(stroke
				(width 0.1)
				(type default)
			)
			(layer "F.Fab")
		)
		(fp_line
			(start 2.500122 -2.999994)
			(end 2.500122 2.999994)
			(stroke
				(width 0.1)
				(type default)
			)
			(layer "F.Fab")
		)
		(fp_line
			(start 2.500122 2.999994)
			(end -2.500122 2.999994)
			(stroke
				(width 0.1)
				(type default)
			)
			(layer "F.Fab")
		)
		(fp_poly
			(pts
				(xy -4.218432 -2.783078) (xy -4.218432 -1.767078) (xy -3.202432 -2.275078)
			)
			(stroke
				(width 0)
				(type default)
			)
			(fill yes)
			(layer "F.Fab")
		)
		(pad "1" smd rect
			(at -2.400046 -2.275078 90)
			(size 0.2286 0.6096)
			(layers "F.Cu" "F.Mask" "F.Paste")
			(net "PVCCIN_CPU0_VOS1")
		)
		(pad "2" smd rect
			(at -2.400046 -1.82499 90)
			(size 0.2286 0.6096)
			(layers "F.Cu" "F.Mask" "F.Paste")
			(net "GND")
		)
		(pad "3" smd rect
			(at -2.400046 -1.374902 90)
			(size 0.2286 0.6096)
			(layers "F.Cu" "F.Mask" "F.Paste")
			(net "PVCCIN_CPU0_VDD1")
		)
		(pad "4" smd rect
			(at -2.400046 -0.925068 90)
			(size 0.2286 0.6096)
			(layers "F.Cu" "F.Mask" "F.Paste")
			(net "PVCCIN_CPU0_PVCC")
		)
		(pad "5" smd rect
			(at -2.400046 -0.47498 90)
			(size 0.2286 0.6096)
			(layers "F.Cu" "F.Mask" "F.Paste")
			(net "GND")
		)
		(pad "6" smd rect
			(at -2.400046 -0.024892 90)
			(size 0.2286 0.6096)
			(layers "F.Cu" "F.Mask" "F.Paste")
			(net "Net_8544")
		)
		(pad "7_9-20_24" smd circle
			(at 0 1.150112 90)
			(size 0 0)
			(layers "F.Cu" "F.Mask" "F.Paste")
			(net "GND")
		)
		(pad "10_19" smd rect
			(at 0 2.899918 90)
			(size 0.6096 4.318)
			(layers "F.Cu" "F.Mask" "F.Paste")
			(net "SW_PVCCIN_CPU0_SW1")
		)
		(pad "25_29" smd rect
			(at 1.549908 -1.279906 270)
			(size 2.0574 2.3114)
			(layers "F.Cu" "F.Mask" "F.Paste")
			(net "SW_P12V_PVCCIN_CPU0_FLT")
		)
		(pad "30" smd rect
			(at 2.05994 -2.899918)
			(size 0.2286 0.6096)
			(layers "F.Cu" "F.Mask" "F.Paste")
			(net "SW_P12V_PVCCIN_CPU0_FLT")
		)
		(pad "31" smd rect
			(at 1.610106 -2.899918)
			(size 0.2286 0.6096)
			(layers "F.Cu" "F.Mask" "F.Paste")
			(net "Net_8545")
		)
		(pad "32" smd rect
			(at 1.160018 -2.899918)
			(size 0.2286 0.6096)
			(layers "F.Cu" "F.Mask" "F.Paste")
			(net "SW_PVCCIN_CPU0_BOOTR1")
		)
		(pad "33" smd rect
			(at 0.70993 -2.899918)
			(size 0.2286 0.6096)
			(layers "F.Cu" "F.Mask" "F.Paste")
			(net "SW_PVCCIN_CPU0_BOOT1")
		)
		(pad "34" smd rect
			(at 0.260096 -2.899918)
			(size 0.2286 0.6096)
			(layers "F.Cu" "F.Mask" "F.Paste")
			(net "PVCCIN_CPU0_PWM1")
		)
		(pad "35" smd rect
			(at -0.189992 -2.899918)
			(size 0.2286 0.6096)
			(layers "F.Cu" "F.Mask" "F.Paste")
			(net "PVCCIN_CPU0_VDD1")
		)
		(pad "36" smd rect
			(at -0.64008 -2.899918)
			(size 0.2286 0.6096)
			(layers "F.Cu" "F.Mask" "F.Paste")
			(net "PVCCIN_CPU0_ATSEN")
		)
		(pad "37" smd rect
			(at -1.089914 -2.899918)
			(size 0.2286 0.6096)
			(layers "F.Cu" "F.Mask" "F.Paste")
			(net "PVCCIN_CPU0_LSET1")
		)
		(pad "38" smd rect
			(at -1.540002 -2.899918)
			(size 0.2286 0.6096)
			(layers "F.Cu" "F.Mask" "F.Paste")
			(net "PVCCIN_CPU0_IMON1")
		)
		(pad "39" smd rect
			(at -1.99009 -2.899918)
			(size 0.2286 0.6096)
			(layers "F.Cu" "F.Mask" "F.Paste")
			(net "PVCCIN_CPU0_VREF")
		)
		(pad "40" smd rect
			(at -0.87503 -1.27508)
			(size 1.7526 1.9558)
			(layers "F.Cu" "F.Mask" "F.Paste")
			(net "GND")
		)
		(pad "41" smd rect
			(at -1.525016 0.249936 270)
			(size 0.3048 0.4572)
			(layers "F.Cu" "F.Mask" "F.Paste")
			(net "Net_8543")
		)
		(zone
			(layer "F.Cu")
			(hatch none 0.5)
			(connect_pads
				(clearance 0)
			)
			(min_thickness 0.25)
			(keepout
				(tracks not_allowed)
				(vias allowed)
				(pads allowed)
				(copperpour not_allowed)
				(footprints allowed)
			)
			(placement
				(enabled no)
				(sheetname "")
			)
			(fill
				(thermal_gap 0.5)
				(thermal_bridge_width 0.5)
				(island_removal_mode 0)
			)
			(polygon
				(pts
					(xy 342.437466 -330.716128) (xy 342.437466 -331.465428) (xy 347.43771 -331.465428) (xy 347.43771 -330.716128)
					(xy 347.147388 -330.716128) (xy 347.147388 -331.171804) (xy 342.727788 -331.171804) (xy 342.727788 -330.716128)
				)
			)
		)
		(zone
			(layer "F.Cu")
			(hatch none 0.5)
			(connect_pads
				(clearance 0)
			)
			(min_thickness 0.25)
			(keepout
				(tracks not_allowed)
				(vias allowed)
				(pads allowed)
				(copperpour not_allowed)
				(footprints allowed)
			)
			(placement
				(enabled no)
				(sheetname "")
			)
			(fill
				(thermal_gap 0.5)
				(thermal_bridge_width 0.5)
				(island_removal_mode 0)
			)
			(polygon
				(pts
					(xy 343.691972 -333.634588) (xy 343.986866 -333.634588) (xy 343.986866 -332.966822) (xy 342.437466 -332.966822)
					(xy 342.437466 -333.423514) (xy 343.133172 -333.423514) (xy 343.133172 -333.262986) (xy 343.691972 -333.262986)
				)
			)
		)
	)
)
